(kicad_pcb
	(version 20241229)
	(generator "pcbnew")
	(generator_version "9.0")
	(general
		(thickness 1.711)
		(legacy_teardrops no)
	)
	(paper "A4")
	(title_block
		(title "Antmicro Baseboard for Jetson AGX Thor")
		(date "2026-02-18")
		(rev "1.1.0")
		(company "Antmicro Ltd")
		(comment 1 "www.antmicro.com")
		(comment 9 "footprints 1038-1042 of 1170")
	)
	(layers
		(0 "F.Cu" signal)
		(4 "In1.Cu" signal)
		(6 "In2.Cu" signal)
		(8 "In3.Cu" signal)
		(10 "In4.Cu" jumper)
		(12 "In5.Cu" signal)
		(14 "In6.Cu" signal)
		(16 "In7.Cu" signal)
		(18 "In8.Cu" signal)
		(2 "B.Cu" signal)
		(9 "F.Adhes" user "F.Adhesive")
		(11 "B.Adhes" user "B.Adhesive")
		(13 "F.Paste" user)
		(15 "B.Paste" user)
		(5 "F.SilkS" user "F.Silkscreen")
		(7 "B.SilkS" user "B.Silkscreen")
		(1 "F.Mask" user)
		(3 "B.Mask" user)
		(17 "Dwgs.User" user "User.Drawings")
		(19 "Cmts.User" user "User.Comments")
		(21 "Eco1.User" user "User.Eco1")
		(23 "Eco2.User" user "User.Eco2")
		(25 "Edge.Cuts" user)
		(27 "Margin" user)
		(31 "F.CrtYd" user "F.Courtyard")
		(29 "B.CrtYd" user "B.Courtyard")
		(35 "F.Fab" user)
		(33 "B.Fab" user)
	)
	(footprint "antmicro-footprints:R_0402_1005Metric"
		(layer "B.Cu")
		(at 213.8 80.2 180)
		(descr "Resistor SMD 0402")
		(tags "resistor SMD 0402")
		(property "Reference" "R113"
			(at 0.2 -2.4 0)
			(layer "B.SilkS")
			(effects
				(font
					(size 0.7 0.7)
					(thickness 0.15)
				)
				(justify left bottom mirror)
			)
		)
		(property "Value" "R_1k_0402"
			(at -1.011843 -1.772046 0)
			(layer "B.Fab")
			(effects
				(font
					(size 0.7 0.7)
					(thickness 0.15)
				)
				(justify left bottom mirror)
			)
		)
		(property "Datasheet" "https://www.bourns.com/docs/product-datasheets/cr.pdf"
			(at 0 0 0)
			(layer "B.Fab")
			(hide yes)
			(effects
				(font
					(size 1.27 1.27)
					(thickness 0.15)
				)
				(justify mirror)
			)
		)
		(property "Description" "SMD Chip Resistor, 1 kohm, ± 1%, 63 mW, 0402 [1005 Metric], Thick Film, General Purpose"
			(at 0 0 0)
			(layer "B.Fab")
			(hide yes)
			(effects
				(font
					(size 1.27 1.27)
					(thickness 0.15)
				)
				(justify mirror)
			)
		)
		(property "MPN" "CR0402-FX-1001GLF"
			(at 0 0 0)
			(unlocked yes)
			(layer "B.Fab")
			(hide yes)
			(effects
				(font
					(size 1 1)
					(thickness 0.15)
				)
				(justify mirror)
			)
		)
		(property "Manufacturer" "Bourns"
			(at 0 0 0)
			(unlocked yes)
			(layer "B.Fab")
			(hide yes)
			(effects
				(font
					(size 1 1)
					(thickness 0.15)
				)
				(justify mirror)
			)
		)
		(property "License" "Apache-2.0"
			(at 0 0 0)
			(unlocked yes)
			(layer "B.Fab")
			(hide yes)
			(effects
				(font
					(size 1 1)
					(thickness 0.15)
				)
				(justify mirror)
			)
		)
		(property "Author" "Antmicro"
			(at 0 0 0)
			(unlocked yes)
			(layer "B.Fab")
			(hide yes)
			(effects
				(font
					(size 1 1)
					(thickness 0.15)
				)
				(justify mirror)
			)
		)
		(property "Val" "1k"
			(at 0 0 0)
			(unlocked yes)
			(layer "B.Fab")
			(hide yes)
			(effects
				(font
					(size 1 1)
					(thickness 0.15)
				)
				(justify mirror)
			)
		)
		(property "Tolerance" "1%"
			(at 0 0 0)
			(unlocked yes)
			(layer "B.Fab")
			(hide yes)
			(effects
				(font
					(size 1 1)
					(thickness 0.15)
				)
				(justify mirror)
			)
		)
		(sheetname "/USB Debug, PD/")
		(sheetfile "usb_debug_pd.kicad_sch")
		(attr smd)
		(fp_poly
			(pts
				(xy -0.925 0.47) (xy -0.925 -0.47) (xy 0.925 -0.47) (xy 0.925 0.47)
			)
			(stroke
				(width 0.05)
				(type default)
			)
			(fill no)
			(layer "B.CrtYd")
		)
		(fp_poly
			(pts
				(xy -0.5 0.25) (xy -0.5 -0.25) (xy 0.5 -0.25) (xy 0.5 0.25)
			)
			(stroke
				(width 0.15)
				(type solid)
			)
			(fill no)
			(layer "B.Fab")
		)
		(fp_text user "License: Apache-2.0"
			(at -0.949999 -5.169 0)
			(layer "B.Fab")
			(effects
				(font
					(size 0.7 0.7)
					(thickness 0.15)
				)
				(justify left bottom mirror)
			)
		)
		(fp_text user "Author: Antmicro"
			(at -0.95 -4.169 0)
			(layer "B.Fab")
			(effects
				(font
					(size 0.7 0.7)
					(thickness 0.15)
				)
				(justify left bottom mirror)
			)
		)
		(fp_text user "${REFERENCE}"
			(at -0.95 -3.168 0)
			(layer "B.Fab")
			(effects
				(font
					(size 0.7 0.7)
					(thickness 0.15)
				)
				(justify left bottom mirror)
			)
		)
		(pad "1" smd roundrect
			(at -0.48 0 180)
			(size 0.59 0.64)
			(layers "B.Cu" "B.Mask" "B.Paste")
			(roundrect_rratio 0.25)
			(net 955 "/USB Debug, PD/FTDI_CBUS3{slash}SCL")
			(pintype "passive")
		)
		(pad "2" smd roundrect
			(at 0.48 0 180)
			(size 0.59 0.64)
			(layers "B.Cu" "B.Mask" "B.Paste")
			(roundrect_rratio 0.25)
			(net 334 "/USB Debug, PD/FTDI_3V3")
			(pintype "passive")
		)
	)
	(footprint "antmicro-footprints:R_0402_1005Metric"
		(layer "B.Cu")
		(at 193.7 87.8 90)
		(descr "Resistor SMD 0402")
		(tags "resistor SMD 0402")
		(property "Reference" "R384"
			(at -3.7 -0.4 270)
			(layer "B.SilkS")
			(effects
				(font
					(size 0.7 0.7)
					(thickness 0.15)
				)
				(justify right top mirror)
			)
		)
		(property "Value" "R_0R_0402"
			(at -1.011843 -1.772047 90)
			(layer "B.Fab")
			(effects
				(font
					(size 0.7 0.7)
					(thickness 0.15)
				)
				(justify right top mirror)
			)
		)
		(property "Datasheet" "https://industrial.panasonic.com/cdbs/www-data/pdf/RDA0000/AOA0000C301.pdf"
			(at 0 0 90)
			(layer "B.Fab")
			(hide yes)
			(effects
				(font
					(size 1.27 1.27)
					(thickness 0.15)
				)
				(justify mirror)
			)
		)
		(property "Description" "SMD Chip Resistor, Jumper, 0 ohm, 100 mW, 0402 [1005 Metric], Thick Film, General Purpose"
			(at 0 0 90)
			(layer "B.Fab")
			(hide yes)
			(effects
				(font
					(size 1.27 1.27)
					(thickness 0.15)
				)
				(justify mirror)
			)
		)
		(property "MPN" "ERJ2GE0R00X"
			(at 0 0 270)
			(unlocked yes)
			(layer "B.Fab")
			(hide yes)
			(effects
				(font
					(size 1 1)
					(thickness 0.15)
				)
				(justify mirror)
			)
		)
		(property "Manufacturer" "Panasonic"
			(at 0 0 270)
			(unlocked yes)
			(layer "B.Fab")
			(hide yes)
			(effects
				(font
					(size 1 1)
					(thickness 0.15)
				)
				(justify mirror)
			)
		)
		(property "License" "Apache-2.0"
			(at 0 0 270)
			(unlocked yes)
			(layer "B.Fab")
			(hide yes)
			(effects
				(font
					(size 1 1)
					(thickness 0.15)
				)
				(justify mirror)
			)
		)
		(property "Author" "Antmicro"
			(at 0 0 270)
			(unlocked yes)
			(layer "B.Fab")
			(hide yes)
			(effects
				(font
					(size 1 1)
					(thickness 0.15)
				)
				(justify mirror)
			)
		)
		(property "Val" "0R"
			(at 0 0 270)
			(unlocked yes)
			(layer "B.Fab")
			(hide yes)
			(effects
				(font
					(size 1 1)
					(thickness 0.15)
				)
				(justify mirror)
			)
		)
		(property "Tolerance" "~"
			(at 0 0 270)
			(unlocked yes)
			(layer "B.Fab")
			(hide yes)
			(effects
				(font
					(size 1 1)
					(thickness 0.15)
				)
				(justify mirror)
			)
		)
		(property "Current" "1A"
			(at 0 0 270)
			(unlocked yes)
			(layer "B.Fab")
			(hide yes)
			(effects
				(font
					(size 1 1)
					(thickness 0.15)
				)
				(justify mirror)
			)
		)
		(sheetname "/USB Debug, PD/")
		(sheetfile "usb_debug_pd.kicad_sch")
		(attr smd)
		(fp_rect
			(start -0.925 0.47)
			(end 0.925 -0.47)
			(stroke
				(width 0.05)
				(type default)
			)
			(fill no)
			(layer "B.CrtYd")
		)
		(fp_rect
			(start -0.5 0.25)
			(end 0.5 -0.25)
			(stroke
				(width 0.15)
				(type solid)
			)
			(fill no)
			(layer "B.Fab")
		)
		(fp_text user "${REFERENCE}"
			(at -0.95 -3.168 90)
			(layer "B.Fab")
			(effects
				(font
					(size 0.7 0.7)
					(thickness 0.15)
				)
				(justify right top mirror)
			)
		)
		(fp_text user "Author: Antmicro"
			(at -0.95 -4.169 90)
			(layer "B.Fab")
			(effects
				(font
					(size 0.7 0.7)
					(thickness 0.15)
				)
				(justify right top mirror)
			)
		)
		(fp_text user "License: Apache-2.0"
			(at -0.95 -5.169 90)
			(layer "B.Fab")
			(effects
				(font
					(size 0.7 0.7)
					(thickness 0.15)
				)
				(justify right top mirror)
			)
		)
		(pad "1" smd roundrect
			(at -0.48 0 90)
			(size 0.59 0.64)
			(layers "B.Cu" "B.Mask" "B.Paste")
			(roundrect_rratio 0.25)
			(net 810 "/USB Debug, PD/MISO")
			(pintype "passive")
		)
		(pad "2" smd roundrect
			(at 0.48 0 90)
			(size 0.59 0.64)
			(layers "B.Cu" "B.Mask" "B.Paste")
			(roundrect_rratio 0.25)
			(net 936 "/USB Debug, PD/PDC_MISO")
			(pintype "passive")
		)
	)
	(footprint "antmicro-footprints:TSOT23-6"
		(layer "B.Cu")
		(at 210.5 66 180)
		(property "Reference" "U46"
			(at -2.109001 -1.8 90)
			(layer "B.SilkS")
			(effects
				(font
					(size 0.7 0.7)
					(thickness 0.15)
				)
				(justify right top mirror)
			)
		)
		(property "Value" "AP22615A_TSOT26"
			(at 0 -2.600001 0)
			(layer "B.Fab")
			(effects
				(font
					(size 0.7 0.7)
					(thickness 0.15)
				)
				(justify left bottom mirror)
			)
		)
		(property "Datasheet" "https://www.mouser.com/datasheet/2/115/DIOD_S_A0008958405_1-2543193.pdf"
			(at 0 0 0)
			(layer "B.Fab")
			(hide yes)
			(effects
				(font
					(size 1.27 1.27)
					(thickness 0.15)
				)
				(justify mirror)
			)
		)
		(property "Description" "Power Load Distribution Switch, High Side, Active High, 1 Output, 5.5 V, 3.6 A, 0.04 ohm, TSOT-26-6"
			(at 0 0 0)
			(layer "B.Fab")
			(hide yes)
			(effects
				(font
					(size 1.27 1.27)
					(thickness 0.15)
				)
				(justify mirror)
			)
		)
		(property "MPN" "AP22615AWU-7"
			(at 0 0 0)
			(unlocked yes)
			(layer "B.Fab")
			(hide yes)
			(effects
				(font
					(size 1 1)
					(thickness 0.15)
				)
				(justify mirror)
			)
		)
		(property "Manufacturer" "Diodes Incorporated"
			(at 0 0 0)
			(unlocked yes)
			(layer "B.Fab")
			(hide yes)
			(effects
				(font
					(size 1 1)
					(thickness 0.15)
				)
				(justify mirror)
			)
		)
		(property "Author" "Antmicro"
			(at 0 0 0)
			(unlocked yes)
			(layer "B.Fab")
			(hide yes)
			(effects
				(font
					(size 1 1)
					(thickness 0.15)
				)
				(justify mirror)
			)
		)
		(property "License" "Apache-2.0"
			(at 0 0 0)
			(unlocked yes)
			(layer "B.Fab")
			(hide yes)
			(effects
				(font
					(size 1 1)
					(thickness 0.15)
				)
				(justify mirror)
			)
		)
		(sheetname "/CSI/")
		(sheetfile "csi.kicad_sch")
		(attr smd)
		(fp_line
			(start 1 1.497)
			(end 1 1.375)
			(stroke
				(width 0.15)
				(type solid)
			)
			(layer "B.SilkS")
		)
		(fp_line
			(start 1 1.497)
			(end -1 1.5)
			(stroke
				(width 0.15)
				(type solid)
			)
			(layer "B.SilkS")
		)
		(fp_line
			(start 1 -1.55)
			(end 1 -1.4)
			(stroke
				(width 0.15)
				(type solid)
			)
			(layer "B.SilkS")
		)
		(fp_line
			(start 1 -1.55)
			(end -1 -1.55)
			(stroke
				(width 0.15)
				(type solid)
			)
			(layer "B.SilkS")
		)
		(fp_line
			(start -1 1.5)
			(end -1 1.375)
			(stroke
				(width 0.15)
				(type solid)
			)
			(layer "B.SilkS")
		)
		(fp_line
			(start -1 -1.55)
			(end -1 -1.4)
			(stroke
				(width 0.15)
				(type solid)
			)
			(layer "B.SilkS")
		)
		(fp_circle
			(center -1.44 1.5)
			(end -1.39 1.5)
			(stroke
				(width 0.15)
				(type solid)
			)
			(fill yes)
			(layer "B.SilkS")
		)
		(fp_poly
			(pts
				(xy 1.930001 1.7) (xy 1.930001 -1.7) (xy -1.930001 -1.7) (xy -1.930001 1.7)
			)
			(stroke
				(width 0.05)
				(type solid)
			)
			(fill no)
			(layer "B.CrtYd")
		)
		(fp_line
			(start -0.45 1.520999)
			(end -0.876001 1.096)
			(stroke
				(width 0.15)
				(type solid)
			)
			(layer "B.Fab")
		)
		(fp_poly
			(pts
				(xy 0.875 -1.528) (xy 0.875 1.525) (xy -0.875 1.525) (xy -0.875 -1.528)
			)
			(stroke
				(width 0.15)
				(type solid)
			)
			(fill no)
			(layer "B.Fab")
		)
		(fp_text user "License: Apache-2.0"
			(at -1.93 -6.199 0)
			(layer "B.Fab")
			(effects
				(font
					(size 0.7 0.7)
					(thickness 0.15)
				)
				(justify left bottom mirror)
			)
		)
		(fp_text user "${REFERENCE}"
			(at -1.93 -3.8 0)
			(layer "B.Fab")
			(effects
				(font
					(size 0.7 0.7)
					(thickness 0.15)
				)
				(justify left bottom mirror)
			)
		)
		(fp_text user "Author: Antmicro"
			(at -1.93 -5 0)
			(layer "B.Fab")
			(effects
				(font
					(size 0.7 0.7)
					(thickness 0.15)
				)
				(justify left bottom mirror)
			)
		)
		(pad "1" smd rect
			(at -1.301 0.947 270)
			(size 0.7 1.2)
			(layers "B.Cu" "B.Mask" "B.Paste")
			(net 9 "/CSI/CSIB_5V")
			(pinfunction "OUT")
			(pintype "power_out")
		)
		(pad "2" smd rect
			(at -1.300999 -0.004 270)
			(size 0.7 1.2)
			(layers "B.Cu" "B.Mask" "B.Paste")
			(net 1 "GND")
			(pinfunction "GND")
			(pintype "power_in")
		)
		(pad "3" smd rect
			(at -1.301 -0.954 270)
			(size 0.7 1.2)
			(layers "B.Cu" "B.Mask" "B.Paste")
			(net 117 "/CSI/CAM_CTRL.CSIB_FLG")
			(pinfunction "FLG")
			(pintype "output")
		)
		(pad "4" smd rect
			(at 1.299 -0.954 270)
			(size 0.7 1.2)
			(layers "B.Cu" "B.Mask" "B.Paste")
			(net 123 "/CSI/CAM_CTRL.CSIB_PEN")
			(pinfunction "EN")
			(pintype "input")
		)
		(pad "5" smd rect
			(at 1.299 -0.004 270)
			(size 0.7 1.2)
			(layers "B.Cu" "B.Mask" "B.Paste")
			(net 997 "/CSI/CSIB_5V_ISET")
			(pinfunction "ISET")
			(pintype "passive")
		)
		(pad "6" smd rect
			(at 1.299 0.947 270)
			(size 0.7 1.2)
			(layers "B.Cu" "B.Mask" "B.Paste")
			(net 5 "+5V")
			(pinfunction "IN")
			(pintype "power_in")
		)
	)
	(footprint "antmicro-footprints:TP_SMD_0.75mm"
		(layer "B.Cu")
		(at 124.5 101.5)
		(property "Reference" "TP38"
			(at 0.61 -0.52 0)
			(layer "B.SilkS")
			(effects
				(font
					(size 0.7 0.7)
					(thickness 0.15)
				)
				(justify right top mirror)
			)
		)
		(property "Value" "TP_0.75mm_SMD"
			(at 0 -1.2 0)
			(layer "B.Fab")
			(effects
				(font
					(size 0.7 0.7)
					(thickness 0.15)
				)
				(justify right top mirror)
			)
		)
		(property "Description" "SMT test point"
			(at 0 0 0)
			(layer "B.Fab")
			(hide yes)
			(effects
				(font
					(size 1.27 1.27)
					(thickness 0.15)
				)
				(justify mirror)
			)
		)
		(property "MPN" ""
			(at 0 0 180)
			(unlocked yes)
			(layer "B.Fab")
			(hide yes)
			(effects
				(font
					(size 1 1)
					(thickness 0.15)
				)
				(justify mirror)
			)
		)
		(property "Manufacturer" ""
			(at 0 0 180)
			(unlocked yes)
			(layer "B.Fab")
			(hide yes)
			(effects
				(font
					(size 1 1)
					(thickness 0.15)
				)
				(justify mirror)
			)
		)
		(property "Author" "Antmicro"
			(at 0 0 180)
			(unlocked yes)
			(layer "B.Fab")
			(hide yes)
			(effects
				(font
					(size 1 1)
					(thickness 0.15)
				)
				(justify mirror)
			)
		)
		(property "License" "Apache-2.0"
			(at 0 0 180)
			(unlocked yes)
			(layer "B.Fab")
			(hide yes)
			(effects
				(font
					(size 1 1)
					(thickness 0.15)
				)
				(justify mirror)
			)
		)
		(sheetname "/M.2/")
		(sheetfile "m2.kicad_sch")
		(attr exclude_from_pos_files exclude_from_bom)
		(fp_circle
			(center 0 0)
			(end 0.475 0)
			(stroke
				(width 0.05)
				(type default)
			)
			(fill no)
			(layer "B.CrtYd")
		)
		(fp_text user "${REFERENCE}"
			(at -0.4 -2.7 0)
			(layer "B.Fab")
			(effects
				(font
					(size 0.7 0.7)
					(thickness 0.15)
				)
				(justify right top mirror)
			)
		)
		(fp_text user "License: Apache-2.0"
			(at -0.4 -5.101 0)
			(layer "B.Fab")
			(effects
				(font
					(size 0.7 0.7)
					(thickness 0.15)
				)
				(justify right top mirror)
			)
		)
		(fp_text user "Author: Antmicro"
			(at -0.4 -3.901 0)
			(layer "B.Fab")
			(effects
				(font
					(size 0.7 0.7)
					(thickness 0.15)
				)
				(justify right top mirror)
			)
		)
		(pad "1" smd circle
			(at 0 0)
			(size 0.75 0.75)
			(layers "B.Cu" "B.Mask")
			(net 235 "/M.2/M2_M_SMB_CLK")
			(pinfunction "1")
			(pintype "passive")
		)
	)
	(footprint "antmicro-footprints:R_0402_1005Metric"
		(layer "B.Cu")
		(at 196.67 76.1)
		(descr "Resistor SMD 0402")
		(tags "resistor SMD 0402")
		(property "Reference" "R110"
			(at 0.83 -0.36 0)
			(layer "B.SilkS")
			(effects
				(font
					(size 0.7 0.7)
					(thickness 0.15)
				)
				(justify right top mirror)
			)
		)
		(property "Value" "R_0R_0402"
			(at -1.011843 -1.772047 0)
			(layer "B.Fab")
			(effects
				(font
					(size 0.7 0.7)
					(thickness 0.15)
				)
				(justify right top mirror)
			)
		)
		(property "Datasheet" "https://industrial.panasonic.com/cdbs/www-data/pdf/RDA0000/AOA0000C301.pdf"
			(at 0 0 0)
			(layer "B.Fab")
			(hide yes)
			(effects
				(font
					(size 1.27 1.27)
					(thickness 0.15)
				)
				(justify mirror)
			)
		)
		(property "Description" "SMD Chip Resistor, Jumper, 0 ohm, 100 mW, 0402 [1005 Metric], Thick Film, General Purpose"
			(at 0 0 0)
			(layer "B.Fab")
			(hide yes)
			(effects
				(font
					(size 1.27 1.27)
					(thickness 0.15)
				)
				(justify mirror)
			)
		)
		(property "Manufacturer" "Panasonic"
			(at 0 0 180)
			(unlocked yes)
			(layer "B.Fab")
			(hide yes)
			(effects
				(font
					(size 1 1)
					(thickness 0.15)
				)
				(justify mirror)
			)
		)
		(property "MPN" "ERJ2GE0R00X"
			(at 0 0 180)
			(unlocked yes)
			(layer "B.Fab")
			(hide yes)
			(effects
				(font
					(size 1 1)
					(thickness 0.15)
				)
				(justify mirror)
			)
		)
		(property "Val" "0R"
			(at 0 0 180)
			(unlocked yes)
			(layer "B.Fab")
			(hide yes)
			(effects
				(font
					(size 1 1)
					(thickness 0.15)
				)
				(justify mirror)
			)
		)
		(property "License" "Apache-2.0"
			(at 0 0 180)
			(unlocked yes)
			(layer "B.Fab")
			(hide yes)
			(effects
				(font
					(size 1 1)
					(thickness 0.15)
				)
				(justify mirror)
			)
		)
		(property "Author" "Antmicro"
			(at 0 0 180)
			(unlocked yes)
			(layer "B.Fab")
			(hide yes)
			(effects
				(font
					(size 1 1)
					(thickness 0.15)
				)
				(justify mirror)
			)
		)
		(property "Tolerance" "~"
			(at 0 0 180)
			(unlocked yes)
			(layer "B.Fab")
			(hide yes)
			(effects
				(font
					(size 1 1)
					(thickness 0.15)
				)
				(justify mirror)
			)
		)
		(property "Current" "1A"
			(at 0 0 180)
			(unlocked yes)
			(layer "B.Fab")
			(hide yes)
			(effects
				(font
					(size 1 1)
					(thickness 0.15)
				)
				(justify mirror)
			)
		)
		(sheetname "/USB Debug, PD/")
		(sheetfile "usb_debug_pd.kicad_sch")
		(attr smd)
		(fp_rect
			(start -0.925 0.47)
			(end 0.925 -0.47)
			(stroke
				(width 0.05)
				(type default)
			)
			(fill no)
			(layer "B.CrtYd")
		)
		(fp_rect
			(start -0.5 0.25)
			(end 0.5 -0.25)
			(stroke
				(width 0.15)
				(type solid)
			)
			(fill no)
			(layer "B.Fab")
		)
		(fp_text user "Author: Antmicro"
			(at -0.95 -4.169 0)
			(layer "B.Fab")
			(effects
				(font
					(size 0.7 0.7)
					(thickness 0.15)
				)
				(justify right top mirror)
			)
		)
		(fp_text user "License: Apache-2.0"
			(at -0.95 -5.169 0)
			(layer "B.Fab")
			(effects
				(font
					(size 0.7 0.7)
					(thickness 0.15)
				)
				(justify right top mirror)
			)
		)
		(fp_text user "${REFERENCE}"
			(at -0.95 -3.168 0)
			(layer "B.Fab")
			(effects
				(font
					(size 0.7 0.7)
					(thickness 0.15)
				)
				(justify right top mirror)
			)
		)
		(pad "1" smd roundrect
			(at -0.48 0)
			(size 0.59 0.64)
			(layers "B.Cu" "B.Mask" "B.Paste")
			(roundrect_rratio 0.25)
			(net 954 "/SoM_IO/~{PDC_I2C1_IRQ}")
			(pintype "passive")
		)
		(pad "2" smd roundrect
			(at 0.48 0)
			(size 0.59 0.64)
			(layers "B.Cu" "B.Mask" "B.Paste")
			(roundrect_rratio 0.25)
			(net 953 "/USB Debug, PD/PDC_I2C1_IRQn")
			(pintype "passive")
		)
	)
)
